FILE_TYPE = CONNECTIVITY;
{Allegro Design Entry HDL 17.2-2016 S081 (4005846) 1/11/2022}
"PAGE_NUMBER" = 115;
0"NC";
END.
